(kicad_pcb
	(version 20260206)
	(generator "pcbnew")
	(generator_version "10.0")
	(general
		(thickness 1.6)
		(legacy_teardrops no)
	)
	(paper "A4")
	(title_block
		(title "12092022_DA0F0TFB6D0_F0T_FAN_BOARD_MP5048_D_brd_v02_OCP.brd")
		(comment 1 "Grand Teton / footprints 838-844 of 924")
	)
	(layers
		(0 "F.Cu" signal "TOP")
		(4 "In1.Cu" signal "GND")
		(6 "In2.Cu" signal "IN1")
		(8 "In3.Cu" signal "IN2")
		(10 "In4.Cu" signal "GND1")
		(2 "B.Cu" signal "BOTTOM")
		(9 "F.Adhes" user "F.Adhesive")
		(11 "B.Adhes" user "B.Adhesive")
		(13 "F.Paste" user "Package Geometry/Pastemask Top")
		(15 "B.Paste" user "Package Geometry/Pastemask Bottom")
		(5 "F.SilkS" user "Ref Des/Silkscreen Top")
		(7 "B.SilkS" user "Ref Des/Silkscreen Bottom")
		(1 "F.Mask" user "Board Geometry/Soldermask Top")
		(3 "B.Mask" user "Board Geometry/Soldermask Bottom")
		(17 "Dwgs.User" user "User.Drawings")
		(19 "Cmts.User" user "User.Comments")
		(21 "Eco1.User" user "User.Eco1")
		(23 "Eco2.User" user "User.Eco2")
		(25 "Edge.Cuts" user "Board Geometry/Outline")
		(27 "Margin" user)
		(31 "F.CrtYd" user "Package Geometry/Place Bound Top")
		(29 "B.CrtYd" user "Package Geometry/Place Bound Bottom")
		(35 "F.Fab" user "Ref Des/Assembly Top")
		(33 "B.Fab" user "Ref Des/Assembly Bottom")
	)
	(footprint ""
		(layer "B.Cu")
		(at 2.667 -249.428 90)
		(property "Reference" "PR70"
			(at 0 0 90)
			(layer "B.SilkS")
			(hide yes)
			(effects
				(font
					(size 1.27 1.27)
				)
				(justify mirror)
			)
		)
		(property "Value" ""
			(at 0 0 90)
			(layer "B.Fab")
			(effects
				(font
					(size 1.27 1.27)
				)
				(justify mirror)
			)
		)
		(duplicate_pad_numbers_are_jumpers no)
		(fp_line
			(start 0.7874 -0.4064)
			(end -0.7874 -0.4064)
			(stroke
				(width 0.1524)
				(type default)
			)
			(layer "B.SilkS")
		)
		(fp_line
			(start -0.7874 -0.4064)
			(end -0.7874 0.4064)
			(stroke
				(width 0.1524)
				(type default)
			)
			(layer "B.SilkS")
		)
		(fp_line
			(start 0.7874 0.4064)
			(end 0.7874 -0.4064)
			(stroke
				(width 0.1524)
				(type default)
			)
			(layer "B.SilkS")
		)
		(fp_line
			(start -0.7874 0.4064)
			(end 0.7874 0.4064)
			(stroke
				(width 0.1524)
				(type default)
			)
			(layer "B.SilkS")
		)
		(fp_line
			(start 0.67945 -0.305054)
			(end 0.12065 -0.305054)
			(stroke
				(width 0.1)
				(type default)
			)
			(layer "B.Fab")
		)
		(fp_line
			(start 0.12065 -0.305054)
			(end 0.12065 -0.2794)
			(stroke
				(width 0.1)
				(type default)
			)
			(layer "B.Fab")
		)
		(fp_line
			(start -0.12065 -0.3048)
			(end -0.67945 -0.3048)
			(stroke
				(width 0.1)
				(type default)
			)
			(layer "B.Fab")
		)
		(fp_line
			(start -0.67945 -0.3048)
			(end -0.67945 0.3048)
			(stroke
				(width 0.1)
				(type default)
			)
			(layer "B.Fab")
		)
		(fp_line
			(start 0.12065 -0.2794)
			(end -0.12065 -0.2794)
			(stroke
				(width 0.1)
				(type default)
			)
			(layer "B.Fab")
		)
		(fp_line
			(start -0.12065 -0.2794)
			(end -0.12065 -0.3048)
			(stroke
				(width 0.1)
				(type default)
			)
			(layer "B.Fab")
		)
		(fp_line
			(start 0.12065 0.2794)
			(end 0.12065 0.3048)
			(stroke
				(width 0.1)
				(type default)
			)
			(layer "B.Fab")
		)
		(fp_line
			(start -0.120396 0.2794)
			(end 0.12065 0.2794)
			(stroke
				(width 0.1)
				(type default)
			)
			(layer "B.Fab")
		)
		(fp_line
			(start 0.67945 0.3048)
			(end 0.67945 -0.305054)
			(stroke
				(width 0.1)
				(type default)
			)
			(layer "B.Fab")
		)
		(fp_line
			(start 0.12065 0.3048)
			(end 0.67945 0.3048)
			(stroke
				(width 0.1)
				(type default)
			)
			(layer "B.Fab")
		)
		(fp_line
			(start -0.120396 0.3048)
			(end -0.120396 0.2794)
			(stroke
				(width 0.1)
				(type default)
			)
			(layer "B.Fab")
		)
		(fp_line
			(start -0.67945 0.3048)
			(end -0.120396 0.3048)
			(stroke
				(width 0.1)
				(type default)
			)
			(layer "B.Fab")
		)
		(pad "1" smd circle
			(at 0.40005 0 270)
			(size 0 0)
			(layers "B.Cu" "B.Mask" "B.Paste")
			(net "GND")
		)
		(pad "2" smd circle
			(at -0.40005 0 270)
			(size 0 0)
			(layers "B.Cu" "B.Mask" "B.Paste")
			(net "FAN_6_IMON")
		)
	)
	(footprint ""
		(layer "B.Cu")
		(at 44.6786 -52.6796 180)
		(property "Reference" "C2107"
			(at 0 0 0)
			(layer "B.SilkS")
			(hide yes)
			(effects
				(font
					(size 1.27 1.27)
				)
				(justify mirror)
			)
		)
		(property "Value" ""
			(at 0 0 0)
			(layer "B.Fab")
			(effects
				(font
					(size 1.27 1.27)
				)
				(justify mirror)
			)
		)
		(duplicate_pad_numbers_are_jumpers no)
		(fp_line
			(start 2.2098 0.9398)
			(end 2.2098 -0.9398)
			(stroke
				(width 0.1524)
				(type default)
			)
			(layer "B.SilkS")
		)
		(fp_line
			(start 2.2098 -0.9398)
			(end -2.2098 -0.9398)
			(stroke
				(width 0.1524)
				(type default)
			)
			(layer "B.SilkS")
		)
		(fp_line
			(start -2.2098 0.9398)
			(end 2.2098 0.9398)
			(stroke
				(width 0.1524)
				(type default)
			)
			(layer "B.SilkS")
		)
		(fp_line
			(start -2.2098 -0.9398)
			(end -2.2098 0.9398)
			(stroke
				(width 0.1524)
				(type default)
			)
			(layer "B.SilkS")
		)
		(fp_line
			(start 1.700022 0.899922)
			(end 1.700022 -0.899922)
			(stroke
				(width 0.1)
				(type default)
			)
			(layer "B.Fab")
		)
		(fp_line
			(start 1.700022 -0.899922)
			(end -1.700022 -0.899922)
			(stroke
				(width 0.1)
				(type default)
			)
			(layer "B.Fab")
		)
		(fp_line
			(start -1.700022 0.899922)
			(end 1.700022 0.899922)
			(stroke
				(width 0.1)
				(type default)
			)
			(layer "B.Fab")
		)
		(fp_line
			(start -1.700022 -0.899922)
			(end -1.700022 0.899922)
			(stroke
				(width 0.1)
				(type default)
			)
			(layer "B.Fab")
		)
		(pad "1" smd rect
			(at 1.4732 0 180)
			(size 1.1684 1.5748)
			(layers "B.Cu" "B.Mask" "B.Paste")
			(net "P52V_FAN_3")
		)
		(pad "2" smd rect
			(at -1.4732 0 180)
			(size 1.1684 1.5748)
			(layers "B.Cu" "B.Mask" "B.Paste")
			(net "GND")
		)
	)
	(footprint ""
		(layer "B.Cu")
		(at 38.989 -250.23699 -90)
		(property "Reference" "PC25"
			(at 0 0 90)
			(layer "B.SilkS")
			(hide yes)
			(effects
				(font
					(size 1.27 1.27)
				)
				(justify mirror)
			)
		)
		(property "Value" ""
			(at 0 0 90)
			(layer "B.Fab")
			(effects
				(font
					(size 1.27 1.27)
				)
				(justify mirror)
			)
		)
		(duplicate_pad_numbers_are_jumpers no)
		(fp_line
			(start -0.7874 0.4064)
			(end 0.7874 0.4064)
			(stroke
				(width 0.1524)
				(type default)
			)
			(layer "B.SilkS")
		)
		(fp_line
			(start 0.7874 0.4064)
			(end 0.7874 -0.4064)
			(stroke
				(width 0.1524)
				(type default)
			)
			(layer "B.SilkS")
		)
		(fp_line
			(start -0.7874 -0.4064)
			(end -0.7874 0.4064)
			(stroke
				(width 0.1524)
				(type default)
			)
			(layer "B.SilkS")
		)
		(fp_line
			(start 0.7874 -0.4064)
			(end -0.7874 -0.4064)
			(stroke
				(width 0.1524)
				(type default)
			)
			(layer "B.SilkS")
		)
		(fp_line
			(start -0.67945 0.3048)
			(end -0.120396 0.3048)
			(stroke
				(width 0.1)
				(type default)
			)
			(layer "B.Fab")
		)
		(fp_line
			(start -0.120396 0.3048)
			(end -0.120396 0.2794)
			(stroke
				(width 0.1)
				(type default)
			)
			(layer "B.Fab")
		)
		(fp_line
			(start 0.12065 0.3048)
			(end 0.67945 0.3048)
			(stroke
				(width 0.1)
				(type default)
			)
			(layer "B.Fab")
		)
		(fp_line
			(start 0.67945 0.3048)
			(end 0.67945 -0.305054)
			(stroke
				(width 0.1)
				(type default)
			)
			(layer "B.Fab")
		)
		(fp_line
			(start -0.120396 0.2794)
			(end 0.12065 0.2794)
			(stroke
				(width 0.1)
				(type default)
			)
			(layer "B.Fab")
		)
		(fp_line
			(start 0.12065 0.2794)
			(end 0.12065 0.3048)
			(stroke
				(width 0.1)
				(type default)
			)
			(layer "B.Fab")
		)
		(fp_line
			(start -0.12065 -0.2794)
			(end -0.12065 -0.3048)
			(stroke
				(width 0.1)
				(type default)
			)
			(layer "B.Fab")
		)
		(fp_line
			(start 0.12065 -0.2794)
			(end -0.12065 -0.2794)
			(stroke
				(width 0.1)
				(type default)
			)
			(layer "B.Fab")
		)
		(fp_line
			(start -0.67945 -0.3048)
			(end -0.67945 0.3048)
			(stroke
				(width 0.1)
				(type default)
			)
			(layer "B.Fab")
		)
		(fp_line
			(start -0.12065 -0.3048)
			(end -0.67945 -0.3048)
			(stroke
				(width 0.1)
				(type default)
			)
			(layer "B.Fab")
		)
		(fp_line
			(start 0.12065 -0.305054)
			(end 0.12065 -0.2794)
			(stroke
				(width 0.1)
				(type default)
			)
			(layer "B.Fab")
		)
		(fp_line
			(start 0.67945 -0.305054)
			(end 0.12065 -0.305054)
			(stroke
				(width 0.1)
				(type default)
			)
			(layer "B.Fab")
		)
		(pad "1" smd circle
			(at 0.40005 0 90)
			(size 0 0)
			(layers "B.Cu" "B.Mask" "B.Paste")
			(net "FAN_1_P3V_R")
		)
		(pad "2" smd circle
			(at -0.40005 0 90)
			(size 0 0)
			(layers "B.Cu" "B.Mask" "B.Paste")
			(net "GND")
		)
	)
	(footprint ""
		(layer "B.Cu")
		(at 33.147 -250.23699 90)
		(property "Reference" "PR34"
			(at 0 0 90)
			(layer "B.SilkS")
			(hide yes)
			(effects
				(font
					(size 1.27 1.27)
				)
				(justify mirror)
			)
		)
		(property "Value" ""
			(at 0 0 90)
			(layer "B.Fab")
			(effects
				(font
					(size 1.27 1.27)
				)
				(justify mirror)
			)
		)
		(duplicate_pad_numbers_are_jumpers no)
		(fp_line
			(start 0.7874 -0.4064)
			(end -0.7874 -0.4064)
			(stroke
				(width 0.1524)
				(type default)
			)
			(layer "B.SilkS")
		)
		(fp_line
			(start -0.7874 -0.4064)
			(end -0.7874 0.4064)
			(stroke
				(width 0.1524)
				(type default)
			)
			(layer "B.SilkS")
		)
		(fp_line
			(start 0.7874 0.4064)
			(end 0.7874 -0.4064)
			(stroke
				(width 0.1524)
				(type default)
			)
			(layer "B.SilkS")
		)
		(fp_line
			(start -0.7874 0.4064)
			(end 0.7874 0.4064)
			(stroke
				(width 0.1524)
				(type default)
			)
			(layer "B.SilkS")
		)
		(fp_line
			(start 0.67945 -0.305054)
			(end 0.12065 -0.305054)
			(stroke
				(width 0.1)
				(type default)
			)
			(layer "B.Fab")
		)
		(fp_line
			(start 0.12065 -0.305054)
			(end 0.12065 -0.2794)
			(stroke
				(width 0.1)
				(type default)
			)
			(layer "B.Fab")
		)
		(fp_line
			(start -0.12065 -0.3048)
			(end -0.67945 -0.3048)
			(stroke
				(width 0.1)
				(type default)
			)
			(layer "B.Fab")
		)
		(fp_line
			(start -0.67945 -0.3048)
			(end -0.67945 0.3048)
			(stroke
				(width 0.1)
				(type default)
			)
			(layer "B.Fab")
		)
		(fp_line
			(start 0.12065 -0.2794)
			(end -0.12065 -0.2794)
			(stroke
				(width 0.1)
				(type default)
			)
			(layer "B.Fab")
		)
		(fp_line
			(start -0.12065 -0.2794)
			(end -0.12065 -0.3048)
			(stroke
				(width 0.1)
				(type default)
			)
			(layer "B.Fab")
		)
		(fp_line
			(start 0.12065 0.2794)
			(end 0.12065 0.3048)
			(stroke
				(width 0.1)
				(type default)
			)
			(layer "B.Fab")
		)
		(fp_line
			(start -0.120396 0.2794)
			(end 0.12065 0.2794)
			(stroke
				(width 0.1)
				(type default)
			)
			(layer "B.Fab")
		)
		(fp_line
			(start 0.67945 0.3048)
			(end 0.67945 -0.305054)
			(stroke
				(width 0.1)
				(type default)
			)
			(layer "B.Fab")
		)
		(fp_line
			(start 0.12065 0.3048)
			(end 0.67945 0.3048)
			(stroke
				(width 0.1)
				(type default)
			)
			(layer "B.Fab")
		)
		(fp_line
			(start -0.120396 0.3048)
			(end -0.120396 0.2794)
			(stroke
				(width 0.1)
				(type default)
			)
			(layer "B.Fab")
		)
		(fp_line
			(start -0.67945 0.3048)
			(end -0.120396 0.3048)
			(stroke
				(width 0.1)
				(type default)
			)
			(layer "B.Fab")
		)
		(pad "1" smd circle
			(at 0.40005 0 270)
			(size 0 0)
			(layers "B.Cu" "B.Mask" "B.Paste")
			(net "GND")
		)
		(pad "2" smd circle
			(at -0.40005 0 270)
			(size 0 0)
			(layers "B.Cu" "B.Mask" "B.Paste")
			(net "FAN_1_IMON")
		)
	)
	(footprint ""
		(layer "B.Cu")
		(at 9.906 -169.799 180)
		(property "Reference" "C55"
			(at 0 0 0)
			(layer "B.SilkS")
			(hide yes)
			(effects
				(font
					(size 1.27 1.27)
				)
				(justify mirror)
			)
		)
		(property "Value" ""
			(at 0 0 0)
			(layer "B.Fab")
			(effects
				(font
					(size 1.27 1.27)
				)
				(justify mirror)
			)
		)
		(duplicate_pad_numbers_are_jumpers no)
		(fp_line
			(start 0.7874 0.4064)
			(end 0.7874 -0.4064)
			(stroke
				(width 0.1524)
				(type default)
			)
			(layer "B.SilkS")
		)
		(fp_line
			(start 0.7874 -0.4064)
			(end -0.7874 -0.4064)
			(stroke
				(width 0.1524)
				(type default)
			)
			(layer "B.SilkS")
		)
		(fp_line
			(start -0.7874 0.4064)
			(end 0.7874 0.4064)
			(stroke
				(width 0.1524)
				(type default)
			)
			(layer "B.SilkS")
		)
		(fp_line
			(start -0.7874 -0.4064)
			(end -0.7874 0.4064)
			(stroke
				(width 0.1524)
				(type default)
			)
			(layer "B.SilkS")
		)
		(fp_line
			(start 0.67945 0.3048)
			(end 0.67945 -0.305054)
			(stroke
				(width 0.1)
				(type default)
			)
			(layer "B.Fab")
		)
		(fp_line
			(start 0.67945 -0.305054)
			(end 0.12065 -0.305054)
			(stroke
				(width 0.1)
				(type default)
			)
			(layer "B.Fab")
		)
		(fp_line
			(start 0.12065 0.3048)
			(end 0.67945 0.3048)
			(stroke
				(width 0.1)
				(type default)
			)
			(layer "B.Fab")
		)
		(fp_line
			(start 0.12065 0.2794)
			(end 0.12065 0.3048)
			(stroke
				(width 0.1)
				(type default)
			)
			(layer "B.Fab")
		)
		(fp_line
			(start 0.12065 -0.2794)
			(end -0.12065 -0.2794)
			(stroke
				(width 0.1)
				(type default)
			)
			(layer "B.Fab")
		)
		(fp_line
			(start 0.12065 -0.305054)
			(end 0.12065 -0.2794)
			(stroke
				(width 0.1)
				(type default)
			)
			(layer "B.Fab")
		)
		(fp_line
			(start -0.120396 0.3048)
			(end -0.120396 0.2794)
			(stroke
				(width 0.1)
				(type default)
			)
			(layer "B.Fab")
		)
		(fp_line
			(start -0.120396 0.2794)
			(end 0.12065 0.2794)
			(stroke
				(width 0.1)
				(type default)
			)
			(layer "B.Fab")
		)
		(fp_line
			(start -0.12065 -0.2794)
			(end -0.12065 -0.3048)
			(stroke
				(width 0.1)
				(type default)
			)
			(layer "B.Fab")
		)
		(fp_line
			(start -0.12065 -0.3048)
			(end -0.67945 -0.3048)
			(stroke
				(width 0.1)
				(type default)
			)
			(layer "B.Fab")
		)
		(fp_line
			(start -0.67945 0.3048)
			(end -0.120396 0.3048)
			(stroke
				(width 0.1)
				(type default)
			)
			(layer "B.Fab")
		)
		(fp_line
			(start -0.67945 -0.3048)
			(end -0.67945 0.3048)
			(stroke
				(width 0.1)
				(type default)
			)
			(layer "B.Fab")
		)
		(pad "1" smd circle
			(at 0.40005 0)
			(size 0 0)
			(layers "B.Cu" "B.Mask" "B.Paste")
			(net "P3V3_AUX")
		)
		(pad "2" smd circle
			(at -0.40005 0)
			(size 0 0)
			(layers "B.Cu" "B.Mask" "B.Paste")
			(net "GND")
		)
	)
	(footprint ""
		(layer "B.Cu")
		(at 30.48 -67.945)
		(property "Reference" ""
			(at 0 0 0)
			(layer "B.SilkS")
			(hide yes)
			(effects
				(font
					(size 1.27 1.27)
				)
				(justify mirror)
			)
		)
		(property "Value" ""
			(at 0 0 0)
			(layer "B.Fab")
			(effects
				(font
					(size 1.27 1.27)
				)
				(justify mirror)
			)
		)
		(duplicate_pad_numbers_are_jumpers no)
		(pad "1" smd circle
			(at 0 0 180)
			(size 0.9906 0.9906)
			(layers "B.Cu" "B.Mask" "B.Paste")
			(net "Net_125")
		)
		(zone
			(layer "B.Cu")
			(hatch none 0.5)
			(connect_pads
				(clearance 0)
			)
			(min_thickness 0.25)
			(keepout
				(tracks not_allowed)
				(vias allowed)
				(pads allowed)
				(copperpour not_allowed)
				(footprints allowed)
			)
			(placement
				(enabled no)
				(sheetname "")
			)
			(fill
				(thermal_gap 0.5)
				(thermal_bridge_width 0.5)
				(island_removal_mode 0)
			)
			(polygon
				(pts
					(arc
						(start 32.1056 -67.945)
						(mid 28.8544 -67.945)
						(end 32.1056 -67.945)
					)
				)
			)
		)
	)
	(footprint ""
		(layer "B.Cu")
		(at 46.101 -258.572 -90)
		(property "Reference" "PR10"
			(at 0 0 90)
			(layer "B.SilkS")
			(hide yes)
			(effects
				(font
					(size 1.27 1.27)
				)
				(justify mirror)
			)
		)
		(property "Value" ""
			(at 0 0 90)
			(layer "B.Fab")
			(effects
				(font
					(size 1.27 1.27)
				)
				(justify mirror)
			)
		)
		(duplicate_pad_numbers_are_jumpers no)
		(fp_line
			(start -0.7874 0.4064)
			(end 0.7874 0.4064)
			(stroke
				(width 0.1524)
				(type default)
			)
			(layer "B.SilkS")
		)
		(fp_line
			(start 0.7874 0.4064)
			(end 0.7874 -0.4064)
			(stroke
				(width 0.1524)
				(type default)
			)
			(layer "B.SilkS")
		)
		(fp_line
			(start -0.7874 -0.4064)
			(end -0.7874 0.4064)
			(stroke
				(width 0.1524)
				(type default)
			)
			(layer "B.SilkS")
		)
		(fp_line
			(start 0.7874 -0.4064)
			(end -0.7874 -0.4064)
			(stroke
				(width 0.1524)
				(type default)
			)
			(layer "B.SilkS")
		)
		(fp_line
			(start -0.67945 0.3048)
			(end -0.120396 0.3048)
			(stroke
				(width 0.1)
				(type default)
			)
			(layer "B.Fab")
		)
		(fp_line
			(start -0.120396 0.3048)
			(end -0.120396 0.2794)
			(stroke
				(width 0.1)
				(type default)
			)
			(layer "B.Fab")
		)
		(fp_line
			(start 0.12065 0.3048)
			(end 0.67945 0.3048)
			(stroke
				(width 0.1)
				(type default)
			)
			(layer "B.Fab")
		)
		(fp_line
			(start 0.67945 0.3048)
			(end 0.67945 -0.305054)
			(stroke
				(width 0.1)
				(type default)
			)
			(layer "B.Fab")
		)
		(fp_line
			(start -0.120396 0.2794)
			(end 0.12065 0.2794)
			(stroke
				(width 0.1)
				(type default)
			)
			(layer "B.Fab")
		)
		(fp_line
			(start 0.12065 0.2794)
			(end 0.12065 0.3048)
			(stroke
				(width 0.1)
				(type default)
			)
			(layer "B.Fab")
		)
		(fp_line
			(start -0.12065 -0.2794)
			(end -0.12065 -0.3048)
			(stroke
				(width 0.1)
				(type default)
			)
			(layer "B.Fab")
		)
		(fp_line
			(start 0.12065 -0.2794)
			(end -0.12065 -0.2794)
			(stroke
				(width 0.1)
				(type default)
			)
			(layer "B.Fab")
		)
		(fp_line
			(start -0.67945 -0.3048)
			(end -0.67945 0.3048)
			(stroke
				(width 0.1)
				(type default)
			)
			(layer "B.Fab")
		)
		(fp_line
			(start -0.12065 -0.3048)
			(end -0.67945 -0.3048)
			(stroke
				(width 0.1)
				(type default)
			)
			(layer "B.Fab")
		)
		(fp_line
			(start 0.12065 -0.305054)
			(end 0.12065 -0.2794)
			(stroke
				(width 0.1)
				(type default)
			)
			(layer "B.Fab")
		)
		(fp_line
			(start 0.67945 -0.305054)
			(end 0.12065 -0.305054)
			(stroke
				(width 0.1)
				(type default)
			)
			(layer "B.Fab")
		)
		(pad "1" smd circle
			(at 0.40005 0 90)
			(size 0 0)
			(layers "B.Cu" "B.Mask" "B.Paste")
			(net "GND")
		)
		(pad "2" smd circle
			(at -0.40005 0 90)
			(size 0 0)
			(layers "B.Cu" "B.Mask" "B.Paste")
			(net "FAN_0_IMON")
		)
	)
)
